FILE_TYPE = CONNECTIVITY;
{Allegro Design Entry HDL 17.4-2019 S026 (4007227) 1/17/2022}
"PAGE_NUMBER" = 435;
0"NC";
END.
